(kicad_pcb
	(version 20260206)
	(generator "pcbnew")
	(generator_version "10.0")
	(general
		(thickness 1.6)
		(legacy_teardrops no)
	)
	(paper "A4")
	(title_block
		(title "01162023_DA0F0TEBIF0_F0T_Expander_BD_F_brd_V02_OCP.brd")
		(comment 1 "Grand Teton / footprints 2350-2356 of 9728")
	)
	(layers
		(0 "F.Cu" signal "TOP")
		(4 "In1.Cu" signal "GND")
		(6 "In2.Cu" signal "VCC")
		(8 "In3.Cu" signal "VCC1")
		(10 "In4.Cu" signal "GND1")
		(12 "In5.Cu" signal "IN1")
		(14 "In6.Cu" signal "GND2")
		(16 "In7.Cu" signal "IN2")
		(18 "In8.Cu" signal "GND3")
		(20 "In9.Cu" signal "IN3")
		(22 "In10.Cu" signal "GND4")
		(24 "In11.Cu" signal "IN4")
		(26 "In12.Cu" signal "GND5")
		(28 "In13.Cu" signal "IN5")
		(30 "In14.Cu" signal "GND6")
		(32 "In15.Cu" signal "IN6")
		(34 "In16.Cu" signal "GND7")
		(2 "B.Cu" signal "BOTTOM")
		(9 "F.Adhes" user "F.Adhesive")
		(11 "B.Adhes" user "B.Adhesive")
		(13 "F.Paste" user "Package Geometry/Pastemask Top")
		(15 "B.Paste" user "Package Geometry/Pastemask Bottom")
		(5 "F.SilkS" user "Ref Des/Silkscreen Top")
		(7 "B.SilkS" user "Ref Des/Silkscreen Bottom")
		(1 "F.Mask" user "Board Geometry/Soldermask Top")
		(3 "B.Mask" user "Board Geometry/Soldermask Bottom")
		(17 "Dwgs.User" user "User.Drawings")
		(19 "Cmts.User" user "User.Comments")
		(21 "Eco1.User" user "User.Eco1")
		(23 "Eco2.User" user "User.Eco2")
		(25 "Edge.Cuts" user "Board Geometry/Outline")
		(27 "Margin" user)
		(31 "F.CrtYd" user "Package Geometry/Place Bound Top")
		(29 "B.CrtYd" user "Package Geometry/Place Bound Bottom")
		(35 "F.Fab" user "Ref Des/Assembly Top")
		(33 "B.Fab" user "Ref Des/Assembly Bottom")
	)
	(footprint ""
		(layer "F.Cu")
		(at 445.9478 -237.5154 180)
		(property "Reference" "R6601"
			(at 0 0 180)
			(layer "F.SilkS")
			(hide yes)
			(effects
				(font
					(size 1.27 1.27)
				)
			)
		)
		(property "Value" ""
			(at 0 0 180)
			(layer "F.Fab")
			(effects
				(font
					(size 1.27 1.27)
				)
			)
		)
		(duplicate_pad_numbers_are_jumpers no)
		(fp_line
			(start 0.7874 0.4064)
			(end -0.7874 0.4064)
			(stroke
				(width 0.1524)
				(type default)
			)
			(layer "F.SilkS")
		)
		(fp_line
			(start 0.7874 -0.4064)
			(end 0.7874 0.4064)
			(stroke
				(width 0.1524)
				(type default)
			)
			(layer "F.SilkS")
		)
		(fp_line
			(start -0.7874 0.4064)
			(end -0.7874 -0.4064)
			(stroke
				(width 0.1524)
				(type default)
			)
			(layer "F.SilkS")
		)
		(fp_line
			(start -0.7874 -0.4064)
			(end 0.7874 -0.4064)
			(stroke
				(width 0.1524)
				(type default)
			)
			(layer "F.SilkS")
		)
		(fp_line
			(start 0.67945 0.3048)
			(end 0.120396 0.3048)
			(stroke
				(width 0.1)
				(type default)
			)
			(layer "F.Fab")
		)
		(fp_line
			(start 0.67945 -0.3048)
			(end 0.67945 0.3048)
			(stroke
				(width 0.1)
				(type default)
			)
			(layer "F.Fab")
		)
		(fp_line
			(start 0.12065 -0.2794)
			(end 0.12065 -0.3048)
			(stroke
				(width 0.1)
				(type default)
			)
			(layer "F.Fab")
		)
		(fp_line
			(start 0.12065 -0.3048)
			(end 0.67945 -0.3048)
			(stroke
				(width 0.1)
				(type default)
			)
			(layer "F.Fab")
		)
		(fp_line
			(start 0.120396 0.3048)
			(end 0.120396 0.2794)
			(stroke
				(width 0.1)
				(type default)
			)
			(layer "F.Fab")
		)
		(fp_line
			(start 0.120396 0.2794)
			(end -0.12065 0.2794)
			(stroke
				(width 0.1)
				(type default)
			)
			(layer "F.Fab")
		)
		(fp_line
			(start -0.12065 0.3048)
			(end -0.67945 0.3048)
			(stroke
				(width 0.1)
				(type default)
			)
			(layer "F.Fab")
		)
		(fp_line
			(start -0.12065 0.2794)
			(end -0.12065 0.3048)
			(stroke
				(width 0.1)
				(type default)
			)
			(layer "F.Fab")
		)
		(fp_line
			(start -0.12065 -0.2794)
			(end 0.12065 -0.2794)
			(stroke
				(width 0.1)
				(type default)
			)
			(layer "F.Fab")
		)
		(fp_line
			(start -0.12065 -0.305054)
			(end -0.12065 -0.2794)
			(stroke
				(width 0.1)
				(type default)
			)
			(layer "F.Fab")
		)
		(fp_line
			(start -0.67945 0.3048)
			(end -0.67945 -0.305054)
			(stroke
				(width 0.1)
				(type default)
			)
			(layer "F.Fab")
		)
		(fp_line
			(start -0.67945 -0.305054)
			(end -0.12065 -0.305054)
			(stroke
				(width 0.1)
				(type default)
			)
			(layer "F.Fab")
		)
		(pad "1" smd circle
			(at -0.40005 0 180)
			(size 0 0)
			(layers "F.Cu" "F.Mask" "F.Paste")
			(net "RST_CP2108_SDB_R_N")
		)
		(pad "2" smd circle
			(at 0.40005 0 180)
			(size 0 0)
			(layers "F.Cu" "F.Mask" "F.Paste")
			(net "RST_FT4232_R_N")
		)
	)
	(footprint ""
		(layer "F.Cu")
		(at 73.782682 -343.952322 90)
		(property "Reference" "C139"
			(at 0 0 90)
			(layer "F.SilkS")
			(hide yes)
			(effects
				(font
					(size 1.27 1.27)
				)
			)
		)
		(property "Value" ""
			(at 0 0 90)
			(layer "F.Fab")
			(effects
				(font
					(size 1.27 1.27)
				)
			)
		)
		(duplicate_pad_numbers_are_jumpers no)
		(fp_line
			(start 0.299974 -0.150114)
			(end 0.299974 0.150114)
			(stroke
				(width 0.1)
				(type default)
			)
			(layer "F.Fab")
		)
		(fp_line
			(start -0.299974 -0.150114)
			(end 0.299974 -0.150114)
			(stroke
				(width 0.1)
				(type default)
			)
			(layer "F.Fab")
		)
		(fp_line
			(start 0.299974 0.150114)
			(end -0.299974 0.150114)
			(stroke
				(width 0.1)
				(type default)
			)
			(layer "F.Fab")
		)
		(fp_line
			(start -0.299974 0.150114)
			(end -0.299974 -0.150114)
			(stroke
				(width 0.1)
				(type default)
			)
			(layer "F.Fab")
		)
		(pad "1" smd rect
			(at -0.2667 0 90)
			(size 0.3048 0.381)
			(layers "F.Cu" "F.Mask" "F.Paste")
			(net "P5E_PEX0_STN6_TX_DP<106>")
		)
		(pad "2" smd rect
			(at 0.2667 0 90)
			(size 0.3048 0.381)
			(layers "F.Cu" "F.Mask" "F.Paste")
			(net "P5E_PEX0_STN6_TX_C_DP<106>")
		)
	)
	(footprint ""
		(layer "F.Cu")
		(at 368.746532 -58.323734)
		(property "Reference" "PC413"
			(at 0 0 0)
			(layer "F.SilkS")
			(hide yes)
			(effects
				(font
					(size 1.27 1.27)
				)
			)
		)
		(property "Value" ""
			(at 0 0 0)
			(layer "F.Fab")
			(effects
				(font
					(size 1.27 1.27)
				)
			)
		)
		(duplicate_pad_numbers_are_jumpers no)
		(fp_line
			(start -1.524 -0.762)
			(end 1.524 -0.762)
			(stroke
				(width 0.1524)
				(type default)
			)
			(layer "F.SilkS")
		)
		(fp_line
			(start -1.524 0.762)
			(end -1.524 -0.762)
			(stroke
				(width 0.1524)
				(type default)
			)
			(layer "F.SilkS")
		)
		(fp_line
			(start 1.524 -0.762)
			(end 1.524 0.762)
			(stroke
				(width 0.1524)
				(type default)
			)
			(layer "F.SilkS")
		)
		(fp_line
			(start 1.524 0.762)
			(end -1.524 0.762)
			(stroke
				(width 0.1524)
				(type default)
			)
			(layer "F.SilkS")
		)
		(fp_line
			(start -1.1049 -0.724916)
			(end -1.1049 0.724916)
			(stroke
				(width 0.1)
				(type default)
			)
			(layer "F.Fab")
		)
		(fp_line
			(start -1.1049 0.724916)
			(end 1.1049 0.724916)
			(stroke
				(width 0.1)
				(type default)
			)
			(layer "F.Fab")
		)
		(fp_line
			(start 1.1049 -0.724916)
			(end -1.1049 -0.724916)
			(stroke
				(width 0.1)
				(type default)
			)
			(layer "F.Fab")
		)
		(fp_line
			(start 1.1049 0.724916)
			(end 1.1049 -0.724916)
			(stroke
				(width 0.1)
				(type default)
			)
			(layer "F.Fab")
		)
		(pad "1" smd rect
			(at -0.889 0 180)
			(size 1.016 1.27)
			(layers "F.Cu" "F.Mask" "F.Paste")
			(net "GND")
		)
		(pad "2" smd rect
			(at 0.889 0 180)
			(size 1.016 1.27)
			(layers "F.Cu" "F.Mask" "F.Paste")
			(net "P12V_AUX")
		)
	)
	(footprint ""
		(layer "F.Cu")
		(at 206.73949 -293.47287 -90)
		(property "Reference" "U314"
			(at 0.946404 -4.968748 90)
			(unlocked yes)
			(layer "F.SilkS")
			(effects
				(font
					(size 0.7874 0.5842)
					(thickness 0.1524)
				)
				(justify left)
			)
		)
		(property "Value" ""
			(at 0 0 270)
			(layer "F.Fab")
			(effects
				(font
					(size 1.27 1.27)
				)
			)
		)
		(duplicate_pad_numbers_are_jumpers no)
		(fp_line
			(start -1.463548 1.549908)
			(end -1.463548 -1.549908)
			(stroke
				(width 0.1524)
				(type default)
			)
			(layer "F.SilkS")
		)
		(fp_line
			(start 1.463548 1.549908)
			(end -1.463548 1.549908)
			(stroke
				(width 0.1524)
				(type default)
			)
			(layer "F.SilkS")
		)
		(fp_line
			(start 0 -0.762)
			(end 0.762 -1.549908)
			(stroke
				(width 0.1524)
				(type default)
			)
			(layer "F.SilkS")
		)
		(fp_line
			(start -1.463548 -1.549908)
			(end -0.787908 -1.549908)
			(stroke
				(width 0.1524)
				(type default)
			)
			(layer "F.SilkS")
		)
		(fp_line
			(start -0.787908 -1.549908)
			(end 0 -0.762)
			(stroke
				(width 0.1524)
				(type default)
			)
			(layer "F.SilkS")
		)
		(fp_line
			(start 0.762 -1.549908)
			(end 1.463548 -1.549908)
			(stroke
				(width 0.1524)
				(type default)
			)
			(layer "F.SilkS")
		)
		(fp_line
			(start 1.463548 -1.549908)
			(end 1.463548 1.549908)
			(stroke
				(width 0.1524)
				(type default)
			)
			(layer "F.SilkS")
		)
		(fp_poly
			(pts
				(xy -3.4798 -1.359916) (xy -2.86004 -1.050036) (xy -3.4798 -0.740156)
			)
			(stroke
				(width 0)
				(type default)
			)
			(fill yes)
			(layer "F.SilkS")
		)
		(fp_line
			(start -1.549908 1.549908)
			(end -1.549908 -1.549908)
			(stroke
				(width 0.1)
				(type default)
			)
			(layer "F.Fab")
		)
		(fp_line
			(start 1.549908 1.549908)
			(end -1.549908 1.549908)
			(stroke
				(width 0.1)
				(type default)
			)
			(layer "F.Fab")
		)
		(fp_line
			(start -1.549908 -1.549908)
			(end 1.549908 -1.549908)
			(stroke
				(width 0.1)
				(type default)
			)
			(layer "F.Fab")
		)
		(fp_line
			(start 1.549908 -1.549908)
			(end 1.549908 1.549908)
			(stroke
				(width 0.1)
				(type default)
			)
			(layer "F.Fab")
		)
		(fp_poly
			(pts
				(xy -3.4798 -1.359916) (xy -2.86004 -1.050036) (xy -3.4798 -0.740156)
			)
			(stroke
				(width 0)
				(type default)
			)
			(fill yes)
			(layer "F.Fab")
		)
		(pad "1" smd rect
			(at -2.175002 -1.050036)
			(size 0.6096 1.1684)
			(layers "F.Cu" "F.Mask" "F.Paste")
			(net "P1V8_PEX")
		)
		(pad "2" smd rect
			(at -2.175002 -0.32512)
			(size 0.4318 1.1684)
			(layers "F.Cu" "F.Mask" "F.Paste")
			(net "I2C_PEX1_HOST_R_SCL")
		)
		(pad "3" smd rect
			(at -2.175002 0.32512)
			(size 0.4318 1.1684)
			(layers "F.Cu" "F.Mask" "F.Paste")
			(net "I2C_PEX1_HOST_R_SDA")
		)
		(pad "4" smd rect
			(at -2.175002 1.050036)
			(size 0.6096 1.1684)
			(layers "F.Cu" "F.Mask" "F.Paste")
			(net "GND")
		)
		(pad "5" smd rect
			(at 2.175002 1.050036)
			(size 0.6096 1.1684)
			(layers "F.Cu" "F.Mask" "F.Paste")
			(net "PWRGD_P1V8_PEX1_R")
		)
		(pad "6" smd rect
			(at 2.175002 0.32512)
			(size 0.4318 1.1684)
			(layers "F.Cu" "F.Mask" "F.Paste")
			(net "SMB_PEX1_HOST_LS_SDA")
		)
		(pad "7" smd rect
			(at 2.175002 -0.32512)
			(size 0.4318 1.1684)
			(layers "F.Cu" "F.Mask" "F.Paste")
			(net "SMB_PEX1_HOST_LS_SCL")
		)
		(pad "8" smd rect
			(at 2.175002 -1.050036)
			(size 0.6096 1.1684)
			(layers "F.Cu" "F.Mask" "F.Paste")
			(net "P3V3_AUX")
		)
	)
	(footprint ""
		(layer "F.Cu")
		(at 396.94866 -343.952322 90)
		(property "Reference" "C739"
			(at 0 0 90)
			(layer "F.SilkS")
			(hide yes)
			(effects
				(font
					(size 1.27 1.27)
				)
			)
		)
		(property "Value" ""
			(at 0 0 90)
			(layer "F.Fab")
			(effects
				(font
					(size 1.27 1.27)
				)
			)
		)
		(duplicate_pad_numbers_are_jumpers no)
		(fp_line
			(start 0.299974 -0.150114)
			(end 0.299974 0.150114)
			(stroke
				(width 0.1)
				(type default)
			)
			(layer "F.Fab")
		)
		(fp_line
			(start -0.299974 -0.150114)
			(end 0.299974 -0.150114)
			(stroke
				(width 0.1)
				(type default)
			)
			(layer "F.Fab")
		)
		(fp_line
			(start 0.299974 0.150114)
			(end -0.299974 0.150114)
			(stroke
				(width 0.1)
				(type default)
			)
			(layer "F.Fab")
		)
		(fp_line
			(start -0.299974 0.150114)
			(end -0.299974 -0.150114)
			(stroke
				(width 0.1)
				(type default)
			)
			(layer "F.Fab")
		)
		(pad "1" smd rect
			(at -0.2667 0 90)
			(size 0.3048 0.381)
			(layers "F.Cu" "F.Mask" "F.Paste")
			(net "P5E_PEX3_STN5_TX_DN<91>")
		)
		(pad "2" smd rect
			(at 0.2667 0 90)
			(size 0.3048 0.381)
			(layers "F.Cu" "F.Mask" "F.Paste")
			(net "P5E_PEX3_STN5_TX_C_DN<91>")
		)
	)
	(footprint ""
		(layer "F.Cu")
		(at 115.48364 -279.486868 -90)
		(property "Reference" "PR106"
			(at 0 0 270)
			(layer "F.SilkS")
			(hide yes)
			(effects
				(font
					(size 1.27 1.27)
				)
			)
		)
		(property "Value" ""
			(at 0 0 270)
			(layer "F.Fab")
			(effects
				(font
					(size 1.27 1.27)
				)
			)
		)
		(duplicate_pad_numbers_are_jumpers no)
		(fp_line
			(start -0.7874 0.4064)
			(end -0.7874 -0.4064)
			(stroke
				(width 0.1524)
				(type default)
			)
			(layer "F.SilkS")
		)
		(fp_line
			(start 0.7874 0.4064)
			(end -0.7874 0.4064)
			(stroke
				(width 0.1524)
				(type default)
			)
			(layer "F.SilkS")
		)
		(fp_line
			(start -0.7874 -0.4064)
			(end 0.7874 -0.4064)
			(stroke
				(width 0.1524)
				(type default)
			)
			(layer "F.SilkS")
		)
		(fp_line
			(start 0.7874 -0.4064)
			(end 0.7874 0.4064)
			(stroke
				(width 0.1524)
				(type default)
			)
			(layer "F.SilkS")
		)
		(fp_line
			(start -0.67945 0.3048)
			(end -0.67945 -0.305054)
			(stroke
				(width 0.1)
				(type default)
			)
			(layer "F.Fab")
		)
		(fp_line
			(start -0.12065 0.3048)
			(end -0.67945 0.3048)
			(stroke
				(width 0.1)
				(type default)
			)
			(layer "F.Fab")
		)
		(fp_line
			(start 0.120396 0.3048)
			(end 0.120396 0.2794)
			(stroke
				(width 0.1)
				(type default)
			)
			(layer "F.Fab")
		)
		(fp_line
			(start 0.67945 0.3048)
			(end 0.120396 0.3048)
			(stroke
				(width 0.1)
				(type default)
			)
			(layer "F.Fab")
		)
		(fp_line
			(start -0.12065 0.2794)
			(end -0.12065 0.3048)
			(stroke
				(width 0.1)
				(type default)
			)
			(layer "F.Fab")
		)
		(fp_line
			(start 0.120396 0.2794)
			(end -0.12065 0.2794)
			(stroke
				(width 0.1)
				(type default)
			)
			(layer "F.Fab")
		)
		(fp_line
			(start -0.12065 -0.2794)
			(end 0.12065 -0.2794)
			(stroke
				(width 0.1)
				(type default)
			)
			(layer "F.Fab")
		)
		(fp_line
			(start 0.12065 -0.2794)
			(end 0.12065 -0.3048)
			(stroke
				(width 0.1)
				(type default)
			)
			(layer "F.Fab")
		)
		(fp_line
			(start 0.12065 -0.3048)
			(end 0.67945 -0.3048)
			(stroke
				(width 0.1)
				(type default)
			)
			(layer "F.Fab")
		)
		(fp_line
			(start 0.67945 -0.3048)
			(end 0.67945 0.3048)
			(stroke
				(width 0.1)
				(type default)
			)
			(layer "F.Fab")
		)
		(fp_line
			(start -0.67945 -0.305054)
			(end -0.12065 -0.305054)
			(stroke
				(width 0.1)
				(type default)
			)
			(layer "F.Fab")
		)
		(fp_line
			(start -0.12065 -0.305054)
			(end -0.12065 -0.2794)
			(stroke
				(width 0.1)
				(type default)
			)
			(layer "F.Fab")
		)
		(pad "1" smd circle
			(at -0.40005 0 270)
			(size 0 0)
			(layers "F.Cu" "F.Mask" "F.Paste")
			(net "P0V8_PEX0_LSET2")
		)
		(pad "2" smd circle
			(at 0.40005 0 270)
			(size 0 0)
			(layers "F.Cu" "F.Mask" "F.Paste")
			(net "GND")
		)
	)
	(footprint ""
		(layer "F.Cu")
		(at 266.320524 -26.666444 -90)
		(property "Reference" "R4071"
			(at 0 0 270)
			(layer "F.SilkS")
			(hide yes)
			(effects
				(font
					(size 1.27 1.27)
				)
			)
		)
		(property "Value" ""
			(at 0 0 270)
			(layer "F.Fab")
			(effects
				(font
					(size 1.27 1.27)
				)
			)
		)
		(duplicate_pad_numbers_are_jumpers no)
		(fp_line
			(start -0.7874 0.4064)
			(end -0.7874 -0.4064)
			(stroke
				(width 0.1524)
				(type default)
			)
			(layer "F.SilkS")
		)
		(fp_line
			(start 0.7874 0.4064)
			(end -0.7874 0.4064)
			(stroke
				(width 0.1524)
				(type default)
			)
			(layer "F.SilkS")
		)
		(fp_line
			(start -0.7874 -0.4064)
			(end 0.7874 -0.4064)
			(stroke
				(width 0.1524)
				(type default)
			)
			(layer "F.SilkS")
		)
		(fp_line
			(start 0.7874 -0.4064)
			(end 0.7874 0.4064)
			(stroke
				(width 0.1524)
				(type default)
			)
			(layer "F.SilkS")
		)
		(fp_line
			(start -0.67945 0.3048)
			(end -0.67945 -0.305054)
			(stroke
				(width 0.1)
				(type default)
			)
			(layer "F.Fab")
		)
		(fp_line
			(start -0.12065 0.3048)
			(end -0.67945 0.3048)
			(stroke
				(width 0.1)
				(type default)
			)
			(layer "F.Fab")
		)
		(fp_line
			(start 0.120396 0.3048)
			(end 0.120396 0.2794)
			(stroke
				(width 0.1)
				(type default)
			)
			(layer "F.Fab")
		)
		(fp_line
			(start 0.67945 0.3048)
			(end 0.120396 0.3048)
			(stroke
				(width 0.1)
				(type default)
			)
			(layer "F.Fab")
		)
		(fp_line
			(start -0.12065 0.2794)
			(end -0.12065 0.3048)
			(stroke
				(width 0.1)
				(type default)
			)
			(layer "F.Fab")
		)
		(fp_line
			(start 0.120396 0.2794)
			(end -0.12065 0.2794)
			(stroke
				(width 0.1)
				(type default)
			)
			(layer "F.Fab")
		)
		(fp_line
			(start -0.12065 -0.2794)
			(end 0.12065 -0.2794)
			(stroke
				(width 0.1)
				(type default)
			)
			(layer "F.Fab")
		)
		(fp_line
			(start 0.12065 -0.2794)
			(end 0.12065 -0.3048)
			(stroke
				(width 0.1)
				(type default)
			)
			(layer "F.Fab")
		)
		(fp_line
			(start 0.12065 -0.3048)
			(end 0.67945 -0.3048)
			(stroke
				(width 0.1)
				(type default)
			)
			(layer "F.Fab")
		)
		(fp_line
			(start 0.67945 -0.3048)
			(end 0.67945 0.3048)
			(stroke
				(width 0.1)
				(type default)
			)
			(layer "F.Fab")
		)
		(fp_line
			(start -0.67945 -0.305054)
			(end -0.12065 -0.305054)
			(stroke
				(width 0.1)
				(type default)
			)
			(layer "F.Fab")
		)
		(fp_line
			(start -0.12065 -0.305054)
			(end -0.12065 -0.2794)
			(stroke
				(width 0.1)
				(type default)
			)
			(layer "F.Fab")
		)
		(pad "1" smd circle
			(at -0.40005 0 270)
			(size 0 0)
			(layers "F.Cu" "F.Mask" "F.Paste")
			(net "PRSNT_SSD9_R_N")
		)
		(pad "2" smd circle
			(at 0.40005 0 270)
			(size 0 0)
			(layers "F.Cu" "F.Mask" "F.Paste")
			(net "PRSNT_SSD9_N")
		)
	)
)
